# S9S_MB_2U (Grand Teton) — schematic netlist excerpt (pin names and nets, part order shuffled) for the footprints in the layout excerpt that follows; sources: Cadence DE-HDL packaged netlist, KiCad conversion of 03242023_DA0F0TMBIJ0_F0T_Motherboard_J_brd_V01_OCP.brd

R3105  Q_RES  0 5% CHIP  pkg 0402LF  page 234 : A = SMB_BMC_SWB_SCL ; B = SMB_BMC_SWB_R_SCL
R4184  Q_RES  1K 1% EMPTY  pkg 0402LF  page 170 : A = P3V3_AUX ; B = U273_3_ADD2

(kicad_pcb
	(version 20260206)
	(generator "pcbnew")
	(generator_version "10.0")
	(general
		(thickness 1.6)
		(legacy_teardrops no)
	)
	(paper "A4")
	(title_block
		(title "03242023_DA0F0TMBIJ0_F0T_Motherboard_J_brd_V01_OCP.brd")
		(comment 1 "Grand Teton / footprints 3187-3188 of 6105")
	)
	(layers
		(0 "F.Cu" signal "TOP")
		(4 "In1.Cu" signal "GND")
		(6 "In2.Cu" signal "IN1")
		(8 "In3.Cu" signal "GND1")
		(10 "In4.Cu" signal "IN2")
		(12 "In5.Cu" signal "GND2")
		(14 "In6.Cu" signal "IN3")
		(16 "In7.Cu" signal "GND3")
		(18 "In8.Cu" signal "VCC")
		(20 "In9.Cu" signal "VCC1")
		(22 "In10.Cu" signal "GND4")
		(24 "In11.Cu" signal "IN4")
		(26 "In12.Cu" signal "GND5")
		(28 "In13.Cu" signal "IN5")
		(30 "In14.Cu" signal "GND6")
		(32 "In15.Cu" signal "IN6")
		(34 "In16.Cu" signal "GND7")
		(2 "B.Cu" signal "BOTTOM")
		(9 "F.Adhes" user "F.Adhesive")
		(11 "B.Adhes" user "B.Adhesive")
		(13 "F.Paste" user "Package Geometry/Pastemask Top")
		(15 "B.Paste" user "Package Geometry/Pastemask Bottom")
		(5 "F.SilkS" user "Ref Des/Silkscreen Top")
		(7 "B.SilkS" user "Ref Des/Silkscreen Bottom")
		(1 "F.Mask" user "Board Geometry/Soldermask Top")
		(3 "B.Mask" user "Board Geometry/Soldermask Bottom")
		(17 "Dwgs.User" user "User.Drawings")
		(19 "Cmts.User" user "User.Comments")
		(21 "Eco1.User" user "User.Eco1")
		(23 "Eco2.User" user "User.Eco2")
		(25 "Edge.Cuts" user "Board Geometry/Outline")
		(27 "Margin" user)
		(31 "F.CrtYd" user "Package Geometry/Place Bound Top")
		(29 "B.CrtYd" user "Package Geometry/Place Bound Bottom")
		(35 "F.Fab" user "Ref Des/Assembly Top")
		(33 "B.Fab" user "Ref Des/Assembly Bottom")
	)
	(footprint ""
		(layer "F.Cu")
		(at 123.810522 -14.19733 180)
		(property "Reference" "R4184"
			(at 0 0 180)
			(layer "F.SilkS")
			(hide yes)
			(effects
				(font
					(size 1.27 1.27)
				)
			)
		)
		(property "Value" ""
			(at 0 0 180)
			(layer "F.Fab")
			(effects
				(font
					(size 1.27 1.27)
				)
			)
		)
		(duplicate_pad_numbers_are_jumpers no)
		(fp_line
			(start 0.7874 0.4064)
			(end -0.7874 0.4064)
			(stroke
				(width 0.1524)
				(type default)
			)
			(layer "F.SilkS")
		)
		(fp_line
			(start 0.7874 -0.4064)
			(end 0.7874 0.4064)
			(stroke
				(width 0.1524)
				(type default)
			)
			(layer "F.SilkS")
		)
		(fp_line
			(start -0.7874 0.4064)
			(end -0.7874 -0.4064)
			(stroke
				(width 0.1524)
				(type default)
			)
			(layer "F.SilkS")
		)
		(fp_line
			(start -0.7874 -0.4064)
			(end 0.7874 -0.4064)
			(stroke
				(width 0.1524)
				(type default)
			)
			(layer "F.SilkS")
		)
		(fp_line
			(start 0.67945 0.3048)
			(end 0.120396 0.3048)
			(stroke
				(width 0.1)
				(type default)
			)
			(layer "F.Fab")
		)
		(fp_line
			(start 0.67945 -0.3048)
			(end 0.67945 0.3048)
			(stroke
				(width 0.1)
				(type default)
			)
			(layer "F.Fab")
		)
		(fp_line
			(start 0.12065 -0.2794)
			(end 0.12065 -0.3048)
			(stroke
				(width 0.1)
				(type default)
			)
			(layer "F.Fab")
		)
		(fp_line
			(start 0.12065 -0.3048)
			(end 0.67945 -0.3048)
			(stroke
				(width 0.1)
				(type default)
			)
			(layer "F.Fab")
		)
		(fp_line
			(start 0.120396 0.3048)
			(end 0.120396 0.2794)
			(stroke
				(width 0.1)
				(type default)
			)
			(layer "F.Fab")
		)
		(fp_line
			(start 0.120396 0.2794)
			(end -0.12065 0.2794)
			(stroke
				(width 0.1)
				(type default)
			)
			(layer "F.Fab")
		)
		(fp_line
			(start -0.12065 0.3048)
			(end -0.67945 0.3048)
			(stroke
				(width 0.1)
				(type default)
			)
			(layer "F.Fab")
		)
		(fp_line
			(start -0.12065 0.2794)
			(end -0.12065 0.3048)
			(stroke
				(width 0.1)
				(type default)
			)
			(layer "F.Fab")
		)
		(fp_line
			(start -0.12065 -0.2794)
			(end 0.12065 -0.2794)
			(stroke
				(width 0.1)
				(type default)
			)
			(layer "F.Fab")
		)
		(fp_line
			(start -0.12065 -0.305054)
			(end -0.12065 -0.2794)
			(stroke
				(width 0.1)
				(type default)
			)
			(layer "F.Fab")
		)
		(fp_line
			(start -0.67945 0.3048)
			(end -0.67945 -0.305054)
			(stroke
				(width 0.1)
				(type default)
			)
			(layer "F.Fab")
		)
		(fp_line
			(start -0.67945 -0.305054)
			(end -0.12065 -0.305054)
			(stroke
				(width 0.1)
				(type default)
			)
			(layer "F.Fab")
		)
		(pad "1" smd circle
			(at -0.40005 0 180)
			(size 0 0)
			(layers "F.Cu" "F.Mask" "F.Paste")
			(net "P3V3_AUX")
		)
		(pad "2" smd circle
			(at 0.40005 0 180)
			(size 0 0)
			(layers "F.Cu" "F.Mask" "F.Paste")
			(net "U273_3_ADD2")
		)
	)
	(footprint ""
		(layer "F.Cu")
		(at 163.12515 -432.865276 -90)
		(property "Reference" "R3105"
			(at 0 0 270)
			(layer "F.SilkS")
			(hide yes)
			(effects
				(font
					(size 1.27 1.27)
				)
			)
		)
		(property "Value" ""
			(at 0 0 270)
			(layer "F.Fab")
			(effects
				(font
					(size 1.27 1.27)
				)
			)
		)
		(duplicate_pad_numbers_are_jumpers no)
		(fp_line
			(start -0.7874 0.4064)
			(end -0.7874 -0.4064)
			(stroke
				(width 0.1524)
				(type default)
			)
			(layer "F.SilkS")
		)
		(fp_line
			(start 0.7874 0.4064)
			(end -0.7874 0.4064)
			(stroke
				(width 0.1524)
				(type default)
			)
			(layer "F.SilkS")
		)
		(fp_line
			(start -0.7874 -0.4064)
			(end 0.7874 -0.4064)
			(stroke
				(width 0.1524)
				(type default)
			)
			(layer "F.SilkS")
		)
		(fp_line
			(start 0.7874 -0.4064)
			(end 0.7874 0.4064)
			(stroke
				(width 0.1524)
				(type default)
			)
			(layer "F.SilkS")
		)
		(fp_line
			(start -0.67945 0.3048)
			(end -0.67945 -0.305054)
			(stroke
				(width 0.1)
				(type default)
			)
			(layer "F.Fab")
		)
		(fp_line
			(start -0.12065 0.3048)
			(end -0.67945 0.3048)
			(stroke
				(width 0.1)
				(type default)
			)
			(layer "F.Fab")
		)
		(fp_line
			(start 0.120396 0.3048)
			(end 0.120396 0.2794)
			(stroke
				(width 0.1)
				(type default)
			)
			(layer "F.Fab")
		)
		(fp_line
			(start 0.67945 0.3048)
			(end 0.120396 0.3048)
			(stroke
				(width 0.1)
				(type default)
			)
			(layer "F.Fab")
		)
		(fp_line
			(start -0.12065 0.2794)
			(end -0.12065 0.3048)
			(stroke
				(width 0.1)
				(type default)
			)
			(layer "F.Fab")
		)
		(fp_line
			(start 0.120396 0.2794)
			(end -0.12065 0.2794)
			(stroke
				(width 0.1)
				(type default)
			)
			(layer "F.Fab")
		)
		(fp_line
			(start -0.12065 -0.2794)
			(end 0.12065 -0.2794)
			(stroke
				(width 0.1)
				(type default)
			)
			(layer "F.Fab")
		)
		(fp_line
			(start 0.12065 -0.2794)
			(end 0.12065 -0.3048)
			(stroke
				(width 0.1)
				(type default)
			)
			(layer "F.Fab")
		)
		(fp_line
			(start 0.12065 -0.3048)
			(end 0.67945 -0.3048)
			(stroke
				(width 0.1)
				(type default)
			)
			(layer "F.Fab")
		)
		(fp_line
			(start 0.67945 -0.3048)
			(end 0.67945 0.3048)
			(stroke
				(width 0.1)
				(type default)
			)
			(layer "F.Fab")
		)
		(fp_line
			(start -0.67945 -0.305054)
			(end -0.12065 -0.305054)
			(stroke
				(width 0.1)
				(type default)
			)
			(layer "F.Fab")
		)
		(fp_line
			(start -0.12065 -0.305054)
			(end -0.12065 -0.2794)
			(stroke
				(width 0.1)
				(type default)
			)
			(layer "F.Fab")
		)
		(pad "1" smd circle
			(at -0.40005 0 270)
			(size 0 0)
			(layers "F.Cu" "F.Mask" "F.Paste")
			(net "SMB_BMC_SWB_SCL")
		)
		(pad "2" smd circle
			(at 0.40005 0 270)
			(size 0 0)
			(layers "F.Cu" "F.Mask" "F.Paste")
			(net "SMB_BMC_SWB_R_SCL")
		)
	)
)
